FILE_TYPE = MULTI_PHYS_TABLE;

PART 'CONN14_210HP207GBR1'

{========================================================================================}
:VALUE                   | PART_TYPE | MATERIAL | PART_NUMBER    = STANDARD | LIFECYCLE     | PART_NUMBER   | JEDEC_TYPE    | DESCRIPTION                             | MANUFTR | MANUF_PN         | RD_CMPLS_LVL | CMPLS_LVL | CLASS | DIP_SMD | FROM_PJ       | DATA                     | FP_ECN               | EE_CHECK_LIST | CREATOR | CREATEDAY  | PSL | STATUS | ESD_CDM | ESD_HBM | ESD_MM | MSD | PIN_LENGTH_LONG_PIN | PIN_LENGTH_SHORT_PIN ;
{========================================================================================}
 'CONN14_210-HP2-07GBR1' | 'THLF'    | 'IO'     | 'DFHD14MS170'(!) = ''       | ''               | 'DFHD14MS170' |'HEADER2X7XD'| 'CONN DIP HEADER 14P 2R MS(P2.54,H8.6)' | 'PRX'   | '210-HP2-07GBR1' | 'EP(V1)'     | ''        | 'IO'  | 'DIP'   | 'F0T-BOB-JON' | 'PRX_210-HP2-07GBR1.pdf' | '210-HP2-07GBR1.msg' | ''            | ''      | '20211026' | ''  | ''     | ''      | ''      | ''     | ''  | '119 MILS'          | '119 MILS'          
 'CONN14_210-HP2-07GBR1' | 'THLF'    | 'EMPTY'  | 'DFHD14MS170'(!) = ''       | ''               | 'DFHD14MS170' |'HEADER2X7XD'| 'CONN DIP HEADER 14P 2R MS(P2.54,H8.6)' | 'PRX'   | '210-HP2-07GBR1' | 'EP(V1)'     | ''        | 'IO'  | 'DIP'   | 'F0T-BOB-JON' | 'PRX_210-HP2-07GBR1.pdf' | '210-HP2-07GBR1.msg' | ''            | ''      | '20211026' | ''  | ''     | ''      | ''      | ''     | ''  | '119 MILS'          | '119 MILS'          

END_PART

END.

